# BASEBOARD_FAB2 (Tioga Pass) — schematic netlist excerpt (pin names and nets, part order shuffled) for the footprints in the layout excerpt that follows; sources: Cadence DE-HDL packaged netlist, KiCad conversion of Wiwynn_Tioga_Pass_MB.brd

R1E1  RES  10.0 1% CHIP  pkg 0402  page 200 : A = A_HSC_GATE ; B = A_HSC_GATE1_R
C4D22  CAP_A  0.1UF 16V 10% X7R  pkg 0402V  page 102 : A = P3V3_DB1200_R ; B = GND

(kicad_pcb
	(version 20260206)
	(generator "pcbnew")
	(generator_version "10.0")
	(general
		(thickness 1.6)
		(legacy_teardrops no)
	)
	(paper "A4")
	(title_block
		(title "Wiwynn_Tioga_Pass_MB.brd")
		(comment 1 "Tioga Pass / footprints 889-890 of 4770")
	)
	(layers
		(0 "F.Cu" signal "TOP")
		(4 "In1.Cu" signal "L2GND")
		(6 "In2.Cu" signal "L3")
		(8 "In3.Cu" signal "L4GND")
		(10 "In4.Cu" signal "L5")
		(12 "In5.Cu" signal "L6GND")
		(14 "In6.Cu" signal "L7VCC")
		(16 "In7.Cu" signal "L8VCC")
		(18 "In8.Cu" signal "L9GND")
		(20 "In9.Cu" signal "L10")
		(22 "In10.Cu" signal "L11GND")
		(24 "In11.Cu" signal "L12")
		(26 "In12.Cu" signal "L13GND")
		(2 "B.Cu" signal "BOTTOM")
		(9 "F.Adhes" user "F.Adhesive")
		(11 "B.Adhes" user "B.Adhesive")
		(13 "F.Paste" user "Package Geometry/Pastemask Top")
		(15 "B.Paste" user "Package Geometry/Pastemask Bottom")
		(5 "F.SilkS" user "Ref Des/Silkscreen Top")
		(7 "B.SilkS" user "Ref Des/Silkscreen Bottom")
		(1 "F.Mask" user "Board Geometry/Soldermask Top")
		(3 "B.Mask" user "Board Geometry/Soldermask Bottom")
		(17 "Dwgs.User" user "User.Drawings")
		(19 "Cmts.User" user "User.Comments")
		(21 "Eco1.User" user "User.Eco1")
		(23 "Eco2.User" user "User.Eco2")
		(25 "Edge.Cuts" user "Board Geometry/Outline")
		(27 "Margin" user)
		(31 "F.CrtYd" user "Package Geometry/Place Bound Top")
		(29 "B.CrtYd" user "Package Geometry/Place Bound Bottom")
		(35 "F.Fab" user "Ref Des/Assembly Top")
		(33 "B.Fab" user "Ref Des/Assembly Bottom")
	)
	(footprint ""
		(layer "F.Cu")
		(at 169.0878 -74.93 90)
		(property "Reference" "C4D22"
			(at 0 0 90)
			(layer "F.SilkS")
			(hide yes)
			(effects
				(font
					(size 1.27 1.27)
				)
			)
		)
		(property "Value" ""
			(at 0 0 90)
			(layer "F.Fab")
			(effects
				(font
					(size 1.27 1.27)
				)
			)
		)
		(duplicate_pad_numbers_are_jumpers no)
		(fp_poly
			(pts
				(xy 0.3048 -0.1016) (xy 0.3048 0.9906) (xy -0.3048 0.9906) (xy -0.3048 -0.1016)
			)
			(stroke
				(width 0)
				(type default)
			)
			(fill no)
			(layer "F.CrtYd")
		)
		(fp_line
			(start 0.3048 -0.1016)
			(end -0.3048 -0.1016)
			(stroke
				(width 0.1)
				(type default)
			)
			(layer "F.Fab")
		)
		(fp_line
			(start -0.3048 -0.1016)
			(end -0.3048 0.9906)
			(stroke
				(width 0.1)
				(type default)
			)
			(layer "F.Fab")
		)
		(fp_line
			(start 0.3048 0.9906)
			(end 0.3048 -0.1016)
			(stroke
				(width 0.1)
				(type default)
			)
			(layer "F.Fab")
		)
		(fp_line
			(start -0.3048 0.9906)
			(end 0.3048 0.9906)
			(stroke
				(width 0.1)
				(type default)
			)
			(layer "F.Fab")
		)
		(pad "1" smd rect
			(at 0 0 90)
			(size 0.508 0.508)
			(layers "F.Cu" "F.Mask" "F.Paste")
			(net "P3V3_DB1200_R")
		)
		(pad "2" smd rect
			(at 0 0.889 90)
			(size 0.508 0.508)
			(layers "F.Cu" "F.Mask" "F.Paste")
			(net "GND")
		)
		(zone
			(layer "F.Cu")
			(hatch none 0.5)
			(connect_pads
				(clearance 0)
			)
			(min_thickness 0.25)
			(keepout
				(tracks allowed)
				(vias not_allowed)
				(pads allowed)
				(copperpour not_allowed)
				(footprints allowed)
			)
			(placement
				(enabled no)
				(sheetname "")
			)
			(fill
				(thermal_gap 0.5)
				(thermal_bridge_width 0.5)
				(island_removal_mode 0)
			)
			(polygon
				(pts
					(xy 169.3418 -74.676) (xy 169.3418 -75.184) (xy 169.7228 -75.184) (xy 169.7228 -74.676)
				)
			)
		)
		(zone
			(layer "F.Cu")
			(hatch none 0.5)
			(connect_pads
				(clearance 0)
			)
			(min_thickness 0.25)
			(keepout
				(tracks not_allowed)
				(vias allowed)
				(pads allowed)
				(copperpour not_allowed)
				(footprints allowed)
			)
			(placement
				(enabled no)
				(sheetname "")
			)
			(fill
				(thermal_gap 0.5)
				(thermal_bridge_width 0.5)
				(island_removal_mode 0)
			)
			(polygon
				(pts
					(xy 169.7228 -74.676) (xy 169.7228 -75.184) (xy 169.3418 -75.184) (xy 169.3418 -74.676)
				)
			)
		)
	)
	(footprint ""
		(layer "F.Cu")
		(at 24.728932 -61.0362 -90)
		(property "Reference" "R1E1"
			(at 0 0 270)
			(layer "F.SilkS")
			(hide yes)
			(effects
				(font
					(size 1.27 1.27)
				)
			)
		)
		(property "Value" ""
			(at 0 0 270)
			(layer "F.Fab")
			(effects
				(font
					(size 1.27 1.27)
				)
			)
		)
		(duplicate_pad_numbers_are_jumpers no)
		(fp_rect
			(start 0.2794 -0.1016)
			(end -0.2794 0.9906)
			(stroke
				(width 0)
				(type default)
			)
			(fill no)
			(layer "F.CrtYd")
		)
		(fp_line
			(start -0.2794 0.9906)
			(end 0.2794 0.9906)
			(stroke
				(width 0.1)
				(type default)
			)
			(layer "F.Fab")
		)
		(fp_line
			(start 0.2794 0.9906)
			(end 0.2794 -0.1016)
			(stroke
				(width 0.1)
				(type default)
			)
			(layer "F.Fab")
		)
		(fp_line
			(start -0.2794 -0.1016)
			(end -0.2794 0.9906)
			(stroke
				(width 0.1)
				(type default)
			)
			(layer "F.Fab")
		)
		(fp_line
			(start 0.2794 -0.1016)
			(end -0.2794 -0.1016)
			(stroke
				(width 0.1)
				(type default)
			)
			(layer "F.Fab")
		)
		(pad "1" smd rect
			(at 0 0 270)
			(size 0.508 0.508)
			(layers "F.Cu" "F.Mask" "F.Paste")
			(net "A_HSC_GATE")
		)
		(pad "2" smd rect
			(at 0 0.889 270)
			(size 0.508 0.508)
			(layers "F.Cu" "F.Mask" "F.Paste")
			(net "A_HSC_GATE1_R")
		)
		(zone
			(layer "F.Cu")
			(hatch none 0.5)
			(connect_pads
				(clearance 0)
			)
			(min_thickness 0.25)
			(keepout
				(tracks not_allowed)
				(vias allowed)
				(pads allowed)
				(copperpour not_allowed)
				(footprints allowed)
			)
			(placement
				(enabled no)
				(sheetname "")
			)
			(fill
				(thermal_gap 0.5)
				(thermal_bridge_width 0.5)
				(island_removal_mode 0)
			)
			(polygon
				(pts
					(xy 24.474932 -60.7822) (xy 24.474932 -61.2902) (xy 24.093932 -61.2902) (xy 24.093932 -60.7822)
				)
			)
		)
		(zone
			(layer "F.Cu")
			(hatch none 0.5)
			(connect_pads
				(clearance 0)
			)
			(min_thickness 0.25)
			(keepout
				(tracks allowed)
				(vias not_allowed)
				(pads allowed)
				(copperpour not_allowed)
				(footprints allowed)
			)
			(placement
				(enabled no)
				(sheetname "")
			)
			(fill
				(thermal_gap 0.5)
				(thermal_bridge_width 0.5)
				(island_removal_mode 0)
			)
			(polygon
				(pts
					(xy 24.474932 -60.7822) (xy 24.474932 -61.2902) (xy 24.093932 -61.2902) (xy 24.093932 -60.7822)
				)
			)
		)
	)
)
